(kicad_pcb
	(version 20260206)
	(generator "pcbnew")
	(generator_version "10.0")
	(general
		(thickness 1.6)
		(legacy_teardrops no)
	)
	(paper "A4")
	(title_block
		(title "03242023_DA0F0TMBIJ0_F0T_Motherboard_J_brd_V01_OCP.brd")
		(comment 1 "Grand Teton / footprints 815-820 of 6105")
	)
	(layers
		(0 "F.Cu" signal "TOP")
		(4 "In1.Cu" signal "GND")
		(6 "In2.Cu" signal "IN1")
		(8 "In3.Cu" signal "GND1")
		(10 "In4.Cu" signal "IN2")
		(12 "In5.Cu" signal "GND2")
		(14 "In6.Cu" signal "IN3")
		(16 "In7.Cu" signal "GND3")
		(18 "In8.Cu" signal "VCC")
		(20 "In9.Cu" signal "VCC1")
		(22 "In10.Cu" signal "GND4")
		(24 "In11.Cu" signal "IN4")
		(26 "In12.Cu" signal "GND5")
		(28 "In13.Cu" signal "IN5")
		(30 "In14.Cu" signal "GND6")
		(32 "In15.Cu" signal "IN6")
		(34 "In16.Cu" signal "GND7")
		(2 "B.Cu" signal "BOTTOM")
		(9 "F.Adhes" user "F.Adhesive")
		(11 "B.Adhes" user "B.Adhesive")
		(13 "F.Paste" user "Package Geometry/Pastemask Top")
		(15 "B.Paste" user "Package Geometry/Pastemask Bottom")
		(5 "F.SilkS" user "Ref Des/Silkscreen Top")
		(7 "B.SilkS" user "Ref Des/Silkscreen Bottom")
		(1 "F.Mask" user "Board Geometry/Soldermask Top")
		(3 "B.Mask" user "Board Geometry/Soldermask Bottom")
		(17 "Dwgs.User" user "User.Drawings")
		(19 "Cmts.User" user "User.Comments")
		(21 "Eco1.User" user "User.Eco1")
		(23 "Eco2.User" user "User.Eco2")
		(25 "Edge.Cuts" user "Board Geometry/Outline")
		(27 "Margin" user)
		(31 "F.CrtYd" user "Package Geometry/Place Bound Top")
		(29 "B.CrtYd" user "Package Geometry/Place Bound Bottom")
		(35 "F.Fab" user "Ref Des/Assembly Top")
		(33 "B.Fab" user "Ref Des/Assembly Bottom")
	)
	(footprint ""
		(layer "F.Cu")
		(at 152.693624 -52.318412)
		(property "Reference" "U264"
			(at 4.867656 -2.900426 0)
			(unlocked yes)
			(layer "F.SilkS")
			(effects
				(font
					(size 0.7874 0.5842)
					(thickness 0.1524)
				)
			)
		)
		(property "Value" ""
			(at 0 0 0)
			(layer "F.Fab")
			(effects
				(font
					(size 1.27 1.27)
				)
			)
		)
		(duplicate_pad_numbers_are_jumpers no)
		(fp_line
			(start -1.500124 -1.500124)
			(end -1.004062 -1.500124)
			(stroke
				(width 0.1524)
				(type default)
			)
			(layer "F.SilkS")
		)
		(fp_line
			(start -1.500124 -1.004062)
			(end -1.500124 -1.500124)
			(stroke
				(width 0.1524)
				(type default)
			)
			(layer "F.SilkS")
		)
		(fp_line
			(start -1.500124 1.500124)
			(end -1.500124 1.004062)
			(stroke
				(width 0.1524)
				(type default)
			)
			(layer "F.SilkS")
		)
		(fp_line
			(start -1.004062 1.500124)
			(end -1.500124 1.500124)
			(stroke
				(width 0.1524)
				(type default)
			)
			(layer "F.SilkS")
		)
		(fp_line
			(start 1.004062 -1.500124)
			(end 1.500124 -1.500124)
			(stroke
				(width 0.1524)
				(type default)
			)
			(layer "F.SilkS")
		)
		(fp_line
			(start 1.500124 -1.500124)
			(end 1.500124 -1.004062)
			(stroke
				(width 0.1524)
				(type default)
			)
			(layer "F.SilkS")
		)
		(fp_line
			(start 1.500124 1.004062)
			(end 1.500124 1.500124)
			(stroke
				(width 0.1524)
				(type default)
			)
			(layer "F.SilkS")
		)
		(fp_line
			(start 1.500124 1.500124)
			(end 1.004062 1.500124)
			(stroke
				(width 0.1524)
				(type default)
			)
			(layer "F.SilkS")
		)
		(fp_poly
			(pts
				(xy -2.196846 -1.60782) (xy -1.83769 -0.530352) (xy -2.915412 -0.889508)
			)
			(stroke
				(width 0)
				(type default)
			)
			(fill yes)
			(layer "F.SilkS")
		)
		(fp_line
			(start -1.500124 -1.500124)
			(end 1.500124 -1.500124)
			(stroke
				(width 0.1)
				(type default)
			)
			(layer "F.Fab")
		)
		(fp_line
			(start -1.500124 1.500124)
			(end -1.500124 -1.500124)
			(stroke
				(width 0.1)
				(type default)
			)
			(layer "F.Fab")
		)
		(fp_line
			(start 1.500124 -1.500124)
			(end 1.500124 1.500124)
			(stroke
				(width 0.1)
				(type default)
			)
			(layer "F.Fab")
		)
		(fp_line
			(start 1.500124 1.500124)
			(end -1.500124 1.500124)
			(stroke
				(width 0.1)
				(type default)
			)
			(layer "F.Fab")
		)
		(fp_poly
			(pts
				(xy -2.847848 -1.258062) (xy -2.847848 -0.242062) (xy -1.831848 -0.750062)
			)
			(stroke
				(width 0)
				(type default)
			)
			(fill yes)
			(layer "F.Fab")
		)
		(pad "1" smd rect
			(at -1.400048 -0.750062 270)
			(size 0.2286 0.6096)
			(layers "F.Cu" "F.Mask" "F.Paste")
			(net "INA230_4_A1")
		)
		(pad "2" smd rect
			(at -1.400048 -0.249936 270)
			(size 0.2286 0.6096)
			(layers "F.Cu" "F.Mask" "F.Paste")
			(net "INA230_4_A0")
		)
		(pad "3" smd rect
			(at -1.400048 0.249936 270)
			(size 0.2286 0.6096)
			(layers "F.Cu" "F.Mask" "F.Paste")
			(net "M2_0_P3V3_ADC_ALERT_R")
		)
		(pad "4" smd rect
			(at -1.400048 0.750062 270)
			(size 0.2286 0.6096)
			(layers "F.Cu" "F.Mask" "F.Paste")
			(net "SMB_INA230_4_3V3AUX_SDA_R1")
		)
		(pad "5" smd rect
			(at -0.750062 1.400048)
			(size 0.2286 0.6096)
			(layers "F.Cu" "F.Mask" "F.Paste")
			(net "SMB_INA230_4_3V3AUX_SCL_R1")
		)
		(pad "6" smd rect
			(at -0.249936 1.400048)
			(size 0.2286 0.6096)
			(layers "F.Cu" "F.Mask" "F.Paste")
			(net "NC_INA230_4_NC0")
		)
		(pad "7" smd rect
			(at 0.249936 1.400048)
			(size 0.2286 0.6096)
			(layers "F.Cu" "F.Mask" "F.Paste")
			(net "NC_INA230_4_NC1")
		)
		(pad "8" smd rect
			(at 0.750062 1.400048)
			(size 0.2286 0.6096)
			(layers "F.Cu" "F.Mask" "F.Paste")
			(net "NC_INA230_4_NC2")
		)
		(pad "9" smd rect
			(at 1.400048 0.750062 270)
			(size 0.2286 0.6096)
			(layers "F.Cu" "F.Mask" "F.Paste")
			(net "P3V3_AUX")
		)
		(pad "10" smd rect
			(at 1.400048 0.249936 270)
			(size 0.2286 0.6096)
			(layers "F.Cu" "F.Mask" "F.Paste")
			(net "GND")
		)
		(pad "11" smd rect
			(at 1.400048 -0.249936 270)
			(size 0.2286 0.6096)
			(layers "F.Cu" "F.Mask" "F.Paste")
			(net "P3V3")
		)
		(pad "12" smd rect
			(at 1.400048 -0.750062 270)
			(size 0.2286 0.6096)
			(layers "F.Cu" "F.Mask" "F.Paste")
			(net "VSENSE_P12V_INA230_4_INN")
		)
		(pad "13" smd rect
			(at 0.750062 -1.400048)
			(size 0.2286 0.6096)
			(layers "F.Cu" "F.Mask" "F.Paste")
			(net "VSENSE_P12V_INA230_4_INP")
		)
		(pad "14" smd rect
			(at 0.249936 -1.400048)
			(size 0.2286 0.6096)
			(layers "F.Cu" "F.Mask" "F.Paste")
			(net "NC_INA230_4_NC3")
		)
		(pad "15" smd rect
			(at -0.249936 -1.400048)
			(size 0.2286 0.6096)
			(layers "F.Cu" "F.Mask" "F.Paste")
			(net "NC_INA230_4_NC4")
		)
		(pad "16" smd rect
			(at -0.750062 -1.400048)
			(size 0.2286 0.6096)
			(layers "F.Cu" "F.Mask" "F.Paste")
			(net "NC_INA230_4_NC5")
		)
		(pad "TH" smd rect
			(at 0 0)
			(size 1.7018 1.7018)
			(layers "F.Cu" "F.Mask" "F.Paste")
			(net "GND")
		)
		(zone
			(layer "F.Cu")
			(hatch none 0.5)
			(connect_pads
				(clearance 0)
			)
			(min_thickness 0.25)
			(keepout
				(tracks not_allowed)
				(vias allowed)
				(pads allowed)
				(copperpour not_allowed)
				(footprints allowed)
			)
			(placement
				(enabled no)
				(sheetname "")
			)
			(fill
				(thermal_gap 0.5)
				(thermal_bridge_width 0.5)
				(island_removal_mode 0)
			)
			(polygon
				(pts
					(xy 151.649176 -52.343812) (xy 151.649176 -53.36286) (xy 153.738072 -53.36286) (xy 153.738072 -51.273964)
					(xy 151.649176 -51.273964) (xy 151.649176 -52.318412) (xy 151.791924 -52.318412) (xy 151.791924 -51.416712)
					(xy 153.595324 -51.416712) (xy 153.595324 -53.220112) (xy 151.791924 -53.220112) (xy 151.791924 -52.343812)
				)
			)
		)
	)
	(footprint ""
		(layer "F.Cu")
		(at 366.72139 -338.3026 -90)
		(property "Reference" "PC1340"
			(at 0 0 270)
			(layer "F.SilkS")
			(hide yes)
			(effects
				(font
					(size 1.27 1.27)
				)
			)
		)
		(property "Value" ""
			(at 0 0 270)
			(layer "F.Fab")
			(effects
				(font
					(size 1.27 1.27)
				)
			)
		)
		(duplicate_pad_numbers_are_jumpers no)
		(fp_line
			(start -0.7874 0.4064)
			(end -0.7874 -0.4064)
			(stroke
				(width 0.1524)
				(type default)
			)
			(layer "F.SilkS")
		)
		(fp_line
			(start 0.7874 0.4064)
			(end -0.7874 0.4064)
			(stroke
				(width 0.1524)
				(type default)
			)
			(layer "F.SilkS")
		)
		(fp_line
			(start -0.7874 -0.4064)
			(end 0.7874 -0.4064)
			(stroke
				(width 0.1524)
				(type default)
			)
			(layer "F.SilkS")
		)
		(fp_line
			(start 0.7874 -0.4064)
			(end 0.7874 0.4064)
			(stroke
				(width 0.1524)
				(type default)
			)
			(layer "F.SilkS")
		)
		(fp_line
			(start -0.67945 0.3048)
			(end -0.67945 -0.305054)
			(stroke
				(width 0.1)
				(type default)
			)
			(layer "F.Fab")
		)
		(fp_line
			(start -0.12065 0.3048)
			(end -0.67945 0.3048)
			(stroke
				(width 0.1)
				(type default)
			)
			(layer "F.Fab")
		)
		(fp_line
			(start 0.120396 0.3048)
			(end 0.120396 0.2794)
			(stroke
				(width 0.1)
				(type default)
			)
			(layer "F.Fab")
		)
		(fp_line
			(start 0.67945 0.3048)
			(end 0.120396 0.3048)
			(stroke
				(width 0.1)
				(type default)
			)
			(layer "F.Fab")
		)
		(fp_line
			(start -0.12065 0.2794)
			(end -0.12065 0.3048)
			(stroke
				(width 0.1)
				(type default)
			)
			(layer "F.Fab")
		)
		(fp_line
			(start 0.120396 0.2794)
			(end -0.12065 0.2794)
			(stroke
				(width 0.1)
				(type default)
			)
			(layer "F.Fab")
		)
		(fp_line
			(start -0.12065 -0.2794)
			(end 0.12065 -0.2794)
			(stroke
				(width 0.1)
				(type default)
			)
			(layer "F.Fab")
		)
		(fp_line
			(start 0.12065 -0.2794)
			(end 0.12065 -0.3048)
			(stroke
				(width 0.1)
				(type default)
			)
			(layer "F.Fab")
		)
		(fp_line
			(start 0.12065 -0.3048)
			(end 0.67945 -0.3048)
			(stroke
				(width 0.1)
				(type default)
			)
			(layer "F.Fab")
		)
		(fp_line
			(start 0.67945 -0.3048)
			(end 0.67945 0.3048)
			(stroke
				(width 0.1)
				(type default)
			)
			(layer "F.Fab")
		)
		(fp_line
			(start -0.67945 -0.305054)
			(end -0.12065 -0.305054)
			(stroke
				(width 0.1)
				(type default)
			)
			(layer "F.Fab")
		)
		(fp_line
			(start -0.12065 -0.305054)
			(end -0.12065 -0.2794)
			(stroke
				(width 0.1)
				(type default)
			)
			(layer "F.Fab")
		)
		(pad "1" smd circle
			(at -0.40005 0 270)
			(size 0 0)
			(layers "F.Cu" "F.Mask" "F.Paste")
			(net "GND")
		)
		(pad "2" smd circle
			(at 0.40005 0 270)
			(size 0 0)
			(layers "F.Cu" "F.Mask" "F.Paste")
			(net "PVCCIN_CPU0_VREF")
		)
	)
	(footprint ""
		(layer "F.Cu")
		(at 19.216878 -17.623536 90)
		(property "Reference" "C809"
			(at 0 0 90)
			(layer "F.SilkS")
			(hide yes)
			(effects
				(font
					(size 1.27 1.27)
				)
			)
		)
		(property "Value" ""
			(at 0 0 90)
			(layer "F.Fab")
			(effects
				(font
					(size 1.27 1.27)
				)
			)
		)
		(duplicate_pad_numbers_are_jumpers no)
		(fp_line
			(start 0.299974 -0.150114)
			(end 0.299974 0.150114)
			(stroke
				(width 0.1)
				(type default)
			)
			(layer "F.Fab")
		)
		(fp_line
			(start -0.299974 -0.150114)
			(end 0.299974 -0.150114)
			(stroke
				(width 0.1)
				(type default)
			)
			(layer "F.Fab")
		)
		(fp_line
			(start 0.299974 0.150114)
			(end -0.299974 0.150114)
			(stroke
				(width 0.1)
				(type default)
			)
			(layer "F.Fab")
		)
		(fp_line
			(start -0.299974 0.150114)
			(end -0.299974 -0.150114)
			(stroke
				(width 0.1)
				(type default)
			)
			(layer "F.Fab")
		)
		(pad "1" smd rect
			(at -0.2667 0 90)
			(size 0.3048 0.381)
			(layers "F.Cu" "F.Mask" "F.Paste")
			(net "P5E_CPU1_PE1_TX_C_DP<14>")
		)
		(pad "2" smd rect
			(at 0.2667 0 90)
			(size 0.3048 0.381)
			(layers "F.Cu" "F.Mask" "F.Paste")
			(net "P5E_CPU1_PE1_TX_DP<14>")
		)
	)
	(footprint ""
		(layer "F.Cu")
		(at 185.7756 -93.91015 90)
		(property "Reference" "R4771"
			(at 0 0 90)
			(layer "F.SilkS")
			(hide yes)
			(effects
				(font
					(size 1.27 1.27)
				)
			)
		)
		(property "Value" ""
			(at 0 0 90)
			(layer "F.Fab")
			(effects
				(font
					(size 1.27 1.27)
				)
			)
		)
		(duplicate_pad_numbers_are_jumpers no)
		(fp_line
			(start 0.7874 -0.4064)
			(end 0.7874 0.4064)
			(stroke
				(width 0.1524)
				(type default)
			)
			(layer "F.SilkS")
		)
		(fp_line
			(start -0.7874 -0.4064)
			(end 0.7874 -0.4064)
			(stroke
				(width 0.1524)
				(type default)
			)
			(layer "F.SilkS")
		)
		(fp_line
			(start 0.7874 0.4064)
			(end -0.7874 0.4064)
			(stroke
				(width 0.1524)
				(type default)
			)
			(layer "F.SilkS")
		)
		(fp_line
			(start -0.7874 0.4064)
			(end -0.7874 -0.4064)
			(stroke
				(width 0.1524)
				(type default)
			)
			(layer "F.SilkS")
		)
		(fp_line
			(start -0.12065 -0.305054)
			(end -0.12065 -0.2794)
			(stroke
				(width 0.1)
				(type default)
			)
			(layer "F.Fab")
		)
		(fp_line
			(start -0.67945 -0.305054)
			(end -0.12065 -0.305054)
			(stroke
				(width 0.1)
				(type default)
			)
			(layer "F.Fab")
		)
		(fp_line
			(start 0.67945 -0.3048)
			(end 0.67945 0.3048)
			(stroke
				(width 0.1)
				(type default)
			)
			(layer "F.Fab")
		)
		(fp_line
			(start 0.12065 -0.3048)
			(end 0.67945 -0.3048)
			(stroke
				(width 0.1)
				(type default)
			)
			(layer "F.Fab")
		)
		(fp_line
			(start 0.12065 -0.2794)
			(end 0.12065 -0.3048)
			(stroke
				(width 0.1)
				(type default)
			)
			(layer "F.Fab")
		)
		(fp_line
			(start -0.12065 -0.2794)
			(end 0.12065 -0.2794)
			(stroke
				(width 0.1)
				(type default)
			)
			(layer "F.Fab")
		)
		(fp_line
			(start 0.120396 0.2794)
			(end -0.12065 0.2794)
			(stroke
				(width 0.1)
				(type default)
			)
			(layer "F.Fab")
		)
		(fp_line
			(start -0.12065 0.2794)
			(end -0.12065 0.3048)
			(stroke
				(width 0.1)
				(type default)
			)
			(layer "F.Fab")
		)
		(fp_line
			(start 0.67945 0.3048)
			(end 0.120396 0.3048)
			(stroke
				(width 0.1)
				(type default)
			)
			(layer "F.Fab")
		)
		(fp_line
			(start 0.120396 0.3048)
			(end 0.120396 0.2794)
			(stroke
				(width 0.1)
				(type default)
			)
			(layer "F.Fab")
		)
		(fp_line
			(start -0.12065 0.3048)
			(end -0.67945 0.3048)
			(stroke
				(width 0.1)
				(type default)
			)
			(layer "F.Fab")
		)
		(fp_line
			(start -0.67945 0.3048)
			(end -0.67945 -0.305054)
			(stroke
				(width 0.1)
				(type default)
			)
			(layer "F.Fab")
		)
		(pad "1" smd circle
			(at -0.40005 0 90)
			(size 0 0)
			(layers "F.Cu" "F.Mask" "F.Paste")
			(net "HP_LVC3_SCM_HSC_PWRGD")
		)
		(pad "2" smd circle
			(at 0.40005 0 90)
			(size 0 0)
			(layers "F.Cu" "F.Mask" "F.Paste")
			(net "HP_LVC3_SCM_HSC_PWRGD_PLD")
		)
	)
	(footprint ""
		(layer "F.Cu")
		(at 435.17312 -42.140886 180)
		(property "Reference" "R1317"
			(at 0 0 180)
			(layer "F.SilkS")
			(hide yes)
			(effects
				(font
					(size 1.27 1.27)
				)
			)
		)
		(property "Value" ""
			(at 0 0 180)
			(layer "F.Fab")
			(effects
				(font
					(size 1.27 1.27)
				)
			)
		)
		(duplicate_pad_numbers_are_jumpers no)
		(fp_line
			(start 0.7874 0.4064)
			(end -0.7874 0.4064)
			(stroke
				(width 0.1524)
				(type default)
			)
			(layer "F.SilkS")
		)
		(fp_line
			(start 0.7874 -0.4064)
			(end 0.7874 0.4064)
			(stroke
				(width 0.1524)
				(type default)
			)
			(layer "F.SilkS")
		)
		(fp_line
			(start -0.7874 0.4064)
			(end -0.7874 -0.4064)
			(stroke
				(width 0.1524)
				(type default)
			)
			(layer "F.SilkS")
		)
		(fp_line
			(start -0.7874 -0.4064)
			(end 0.7874 -0.4064)
			(stroke
				(width 0.1524)
				(type default)
			)
			(layer "F.SilkS")
		)
		(fp_line
			(start 0.67945 0.3048)
			(end 0.120396 0.3048)
			(stroke
				(width 0.1)
				(type default)
			)
			(layer "F.Fab")
		)
		(fp_line
			(start 0.67945 -0.3048)
			(end 0.67945 0.3048)
			(stroke
				(width 0.1)
				(type default)
			)
			(layer "F.Fab")
		)
		(fp_line
			(start 0.12065 -0.2794)
			(end 0.12065 -0.3048)
			(stroke
				(width 0.1)
				(type default)
			)
			(layer "F.Fab")
		)
		(fp_line
			(start 0.12065 -0.3048)
			(end 0.67945 -0.3048)
			(stroke
				(width 0.1)
				(type default)
			)
			(layer "F.Fab")
		)
		(fp_line
			(start 0.120396 0.3048)
			(end 0.120396 0.2794)
			(stroke
				(width 0.1)
				(type default)
			)
			(layer "F.Fab")
		)
		(fp_line
			(start 0.120396 0.2794)
			(end -0.12065 0.2794)
			(stroke
				(width 0.1)
				(type default)
			)
			(layer "F.Fab")
		)
		(fp_line
			(start -0.12065 0.3048)
			(end -0.67945 0.3048)
			(stroke
				(width 0.1)
				(type default)
			)
			(layer "F.Fab")
		)
		(fp_line
			(start -0.12065 0.2794)
			(end -0.12065 0.3048)
			(stroke
				(width 0.1)
				(type default)
			)
			(layer "F.Fab")
		)
		(fp_line
			(start -0.12065 -0.2794)
			(end 0.12065 -0.2794)
			(stroke
				(width 0.1)
				(type default)
			)
			(layer "F.Fab")
		)
		(fp_line
			(start -0.12065 -0.305054)
			(end -0.12065 -0.2794)
			(stroke
				(width 0.1)
				(type default)
			)
			(layer "F.Fab")
		)
		(fp_line
			(start -0.67945 0.3048)
			(end -0.67945 -0.305054)
			(stroke
				(width 0.1)
				(type default)
			)
			(layer "F.Fab")
		)
		(fp_line
			(start -0.67945 -0.305054)
			(end -0.12065 -0.305054)
			(stroke
				(width 0.1)
				(type default)
			)
			(layer "F.Fab")
		)
		(pad "1" smd circle
			(at -0.40005 0 180)
			(size 0 0)
			(layers "F.Cu" "F.Mask" "F.Paste")
			(net "P1V05_PCH_AUX")
		)
		(pad "2" smd circle
			(at 0.40005 0 180)
			(size 0 0)
			(layers "F.Cu" "F.Mask" "F.Paste")
			(net "PU_BIOS_RCVR_BOOT")
		)
	)
	(footprint ""
		(layer "F.Cu")
		(at 16.645382 -104.76611 90)
		(property "Reference" "R3652"
			(at 0 0 90)
			(layer "F.SilkS")
			(hide yes)
			(effects
				(font
					(size 1.27 1.27)
				)
			)
		)
		(property "Value" ""
			(at 0 0 90)
			(layer "F.Fab")
			(effects
				(font
					(size 1.27 1.27)
				)
			)
		)
		(duplicate_pad_numbers_are_jumpers no)
		(fp_line
			(start 0.7874 -0.4064)
			(end 0.7874 0.4064)
			(stroke
				(width 0.1524)
				(type default)
			)
			(layer "F.SilkS")
		)
		(fp_line
			(start -0.7874 -0.4064)
			(end 0.00127 -0.4064)
			(stroke
				(width 0.1524)
				(type default)
			)
			(layer "F.SilkS")
		)
		(fp_line
			(start 0.01905 0.4064)
			(end -0.7874 0.4064)
			(stroke
				(width 0.1524)
				(type default)
			)
			(layer "F.SilkS")
		)
		(fp_line
			(start -0.12065 -0.305054)
			(end -0.12065 -0.2794)
			(stroke
				(width 0.1)
				(type default)
			)
			(layer "F.Fab")
		)
		(fp_line
			(start -0.67945 -0.305054)
			(end -0.12065 -0.305054)
			(stroke
				(width 0.1)
				(type default)
			)
			(layer "F.Fab")
		)
		(fp_line
			(start 0.67945 -0.3048)
			(end 0.67945 0.3048)
			(stroke
				(width 0.1)
				(type default)
			)
			(layer "F.Fab")
		)
		(fp_line
			(start 0.12065 -0.3048)
			(end 0.67945 -0.3048)
			(stroke
				(width 0.1)
				(type default)
			)
			(layer "F.Fab")
		)
		(fp_line
			(start 0.12065 -0.2794)
			(end 0.12065 -0.3048)
			(stroke
				(width 0.1)
				(type default)
			)
			(layer "F.Fab")
		)
		(fp_line
			(start -0.12065 -0.2794)
			(end 0.12065 -0.2794)
			(stroke
				(width 0.1)
				(type default)
			)
			(layer "F.Fab")
		)
		(fp_line
			(start 0.120396 0.2794)
			(end -0.12065 0.2794)
			(stroke
				(width 0.1)
				(type default)
			)
			(layer "F.Fab")
		)
		(fp_line
			(start -0.12065 0.2794)
			(end -0.12065 0.3048)
			(stroke
				(width 0.1)
				(type default)
			)
			(layer "F.Fab")
		)
		(fp_line
			(start 0.67945 0.3048)
			(end 0.120396 0.3048)
			(stroke
				(width 0.1)
				(type default)
			)
			(layer "F.Fab")
		)
		(fp_line
			(start 0.120396 0.3048)
			(end 0.120396 0.2794)
			(stroke
				(width 0.1)
				(type default)
			)
			(layer "F.Fab")
		)
		(fp_line
			(start -0.12065 0.3048)
			(end -0.67945 0.3048)
			(stroke
				(width 0.1)
				(type default)
			)
			(layer "F.Fab")
		)
		(fp_line
			(start -0.67945 0.3048)
			(end -0.67945 -0.305054)
			(stroke
				(width 0.1)
				(type default)
			)
			(layer "F.Fab")
		)
		(pad "1" smd rect
			(at -0.40005 0 270)
			(size 0.4572 0.508)
			(layers "F.Cu" "F.Mask" "F.Paste")
			(net "USB2_P0_R_DN")
		)
		(pad "2" smd rect
			(at 0.40005 0 270)
			(size 0.4572 0.508)
			(layers "F.Cu" "F.Mask" "F.Paste")
			(net "USB2_HOST_BMC_B_DN")
		)
	)
)
